(kicad_pcb
	(version 20260206)
	(generator "pcbnew")
	(generator_version "10.0")
	(general
		(thickness 1.6)
		(legacy_teardrops no)
	)
	(paper "A4")
	(title_block
		(title "panther-plus-userver — 13130-1b_20150205.brd")
		(comment 1 "Honey Badger (Wiwynn) / footprints 1250-1257 of 1509")
	)
	(layers
		(0 "F.Cu" signal "TOP")
		(4 "In1.Cu" signal "L2")
		(6 "In2.Cu" signal "L3")
		(8 "In3.Cu" signal "L4")
		(10 "In4.Cu" signal "L5")
		(12 "In5.Cu" signal "L6")
		(14 "In6.Cu" signal "L7")
		(16 "In7.Cu" signal "L8")
		(18 "In8.Cu" signal "L9")
		(20 "In9.Cu" signal "L10")
		(22 "In10.Cu" signal "L11")
		(2 "B.Cu" signal "BOTTOM")
		(9 "F.Adhes" user "F.Adhesive")
		(11 "B.Adhes" user "B.Adhesive")
		(13 "F.Paste" user "Package Geometry/Pastemask Top")
		(15 "B.Paste" user "Package Geometry/Pastemask Bottom")
		(5 "F.SilkS" user "Ref Des/Silkscreen Top")
		(7 "B.SilkS" user "Ref Des/Silkscreen Bottom")
		(1 "F.Mask" user "Board Geometry/Soldermask Top")
		(3 "B.Mask" user "Board Geometry/Soldermask Bottom")
		(17 "Dwgs.User" user "User.Drawings")
		(19 "Cmts.User" user "User.Comments")
		(21 "Eco1.User" user "User.Eco1")
		(23 "Eco2.User" user "User.Eco2")
		(25 "Edge.Cuts" user "Board Geometry/Outline")
		(27 "Margin" user)
		(31 "F.CrtYd" user "Package Geometry/Place Bound Top")
		(29 "B.CrtYd" user "Package Geometry/Place Bound Bottom")
		(35 "F.Fab" user "Ref Des/Assembly Top")
		(33 "B.Fab" user "Ref Des/Assembly Bottom")
	)
	(footprint ""
		(layer "B.Cu")
		(at 34.671 -16.256 90)
		(property "Reference" "R436"
			(at 0 0 90)
			(layer "B.SilkS")
			(hide yes)
			(effects
				(font
					(size 1.27 1.27)
				)
				(justify mirror)
			)
		)
		(property "Value" "0R2J-2-GP"
			(at -1.7907 -1.1176 90)
			(unlocked yes)
			(layer "B.Fab")
			(hide yes)
			(effects
				(font
					(size 1.016 1.016)
					(thickness 0.1524)
				)
				(justify mirror)
			)
		)
		(property "Device Type" "R402H16"
			(at -1.7907 -2.6416 90)
			(unlocked yes)
			(layer "B.Fab")
			(hide yes)
			(effects
				(font
					(size 1.016 1.016)
					(thickness 0.1524)
				)
				(justify mirror)
			)
		)
		(duplicate_pad_numbers_are_jumpers no)
		(fp_rect
			(start 0.381 0.8382)
			(end -0.381 -0.8382)
			(stroke
				(width 0)
				(type default)
			)
			(fill no)
			(layer "B.CrtYd")
		)
		(fp_rect
			(start 0.381 0.8382)
			(end -0.381 -0.8382)
			(stroke
				(width 0)
				(type default)
			)
			(fill no)
			(layer "B.Fab")
		)
		(pad "1" smd custom
			(at 0 -0.4318 270)
			(size 0.127 0.127)
			(layers "B.Cu" "B.Mask" "B.Paste")
			(net "SMBUS_HOST_DATA")
			(options
				(clearance outline)
				(anchor circle)
			)
			(primitives
				(gr_poly
					(pts
						(arc
							(start -0.2032 0.2794)
							(mid -0.239121 0.264521)
							(end -0.254 0.2286)
						)
						(arc
							(start -0.254 -0.2286)
							(mid -0.239121 -0.264521)
							(end -0.2032 -0.2794)
						)
						(arc
							(start 0.2032 -0.2794)
							(mid 0.239121 -0.264521)
							(end 0.254 -0.2286)
						)
						(arc
							(start 0.254 0.2286)
							(mid 0.239121 0.264521)
							(end 0.2032 0.2794)
						)
					)
					(width 0)
					(fill yes)
				)
			)
		)
		(pad "2" smd custom
			(at 0 0.4318 270)
			(size 0.127 0.127)
			(layers "B.Cu" "B.Mask" "B.Paste")
			(net "SMB_CLKBUFF_R_DATA")
			(options
				(clearance outline)
				(anchor circle)
			)
			(primitives
				(gr_poly
					(pts
						(arc
							(start -0.2032 0.2794)
							(mid -0.239121 0.264521)
							(end -0.254 0.2286)
						)
						(arc
							(start -0.254 -0.2286)
							(mid -0.239121 -0.264521)
							(end -0.2032 -0.2794)
						)
						(arc
							(start 0.2032 -0.2794)
							(mid 0.239121 -0.264521)
							(end 0.254 -0.2286)
						)
						(arc
							(start 0.254 0.2286)
							(mid 0.239121 0.264521)
							(end 0.2032 0.2794)
						)
					)
					(width 0)
					(fill yes)
				)
			)
		)
	)
	(footprint ""
		(layer "B.Cu")
		(at 74.041 -27.94 90)
		(property "Reference" "R362"
			(at 0 0 90)
			(layer "B.SilkS")
			(hide yes)
			(effects
				(font
					(size 1.27 1.27)
				)
				(justify mirror)
			)
		)
		(property "Value" "10KR2F-2-GP"
			(at -0.064008 -3.993896 90)
			(unlocked yes)
			(layer "B.Fab")
			(hide yes)
			(effects
				(font
					(size 1.016 1.016)
					(thickness 0.1524)
				)
				(justify mirror)
			)
		)
		(property "Device Type" "R402H16"
			(at -0.064008 -5.517896 90)
			(unlocked yes)
			(layer "B.Fab")
			(hide yes)
			(effects
				(font
					(size 1.016 1.016)
					(thickness 0.1524)
				)
				(justify mirror)
			)
		)
		(duplicate_pad_numbers_are_jumpers no)
		(fp_rect
			(start 0.381 0.8382)
			(end -0.381 -0.8382)
			(stroke
				(width 0)
				(type default)
			)
			(fill no)
			(layer "B.CrtYd")
		)
		(fp_rect
			(start 0.381 0.8382)
			(end -0.381 -0.8382)
			(stroke
				(width 0)
				(type default)
			)
			(fill no)
			(layer "B.Fab")
		)
		(pad "1" smd custom
			(at 0 -0.4318 270)
			(size 0.127 0.127)
			(layers "B.Cu" "B.Mask" "B.Paste")
			(net "P3V3_CPU")
			(options
				(clearance outline)
				(anchor circle)
			)
			(primitives
				(gr_poly
					(pts
						(arc
							(start -0.2032 0.2794)
							(mid -0.239121 0.264521)
							(end -0.254 0.2286)
						)
						(arc
							(start -0.254 -0.2286)
							(mid -0.239121 -0.264521)
							(end -0.2032 -0.2794)
						)
						(arc
							(start 0.2032 -0.2794)
							(mid 0.239121 -0.264521)
							(end 0.254 -0.2286)
						)
						(arc
							(start 0.254 0.2286)
							(mid 0.239121 0.264521)
							(end 0.2032 0.2794)
						)
					)
					(width 0)
					(fill yes)
				)
			)
		)
		(pad "2" smd custom
			(at 0 0.4318 270)
			(size 0.127 0.127)
			(layers "B.Cu" "B.Mask" "B.Paste")
			(net "GBE_SMBALRT#")
			(options
				(clearance outline)
				(anchor circle)
			)
			(primitives
				(gr_poly
					(pts
						(arc
							(start -0.2032 0.2794)
							(mid -0.239121 0.264521)
							(end -0.254 0.2286)
						)
						(arc
							(start -0.254 -0.2286)
							(mid -0.239121 -0.264521)
							(end -0.2032 -0.2794)
						)
						(arc
							(start 0.2032 -0.2794)
							(mid 0.239121 -0.264521)
							(end 0.254 -0.2286)
						)
						(arc
							(start 0.254 0.2286)
							(mid 0.239121 0.264521)
							(end 0.2032 0.2794)
						)
					)
					(width 0)
					(fill yes)
				)
			)
		)
	)
	(footprint ""
		(layer "B.Cu")
		(at 49.657 -30.5308 -90)
		(property "Reference" "L10"
			(at 0 0 90)
			(layer "B.SilkS")
			(hide yes)
			(effects
				(font
					(size 1.27 1.27)
				)
				(justify mirror)
			)
		)
		(property "Value" "BLM18PG330SN1D-GP"
			(at 0.0254 -2.0193 270)
			(unlocked yes)
			(layer "B.Fab")
			(hide yes)
			(effects
				(font
					(size 1.016 1.016)
					(thickness 0.1524)
				)
				(justify mirror)
			)
		)
		(property "Device Type" "L1608-UH38"
			(at 0.0254 -3.5433 270)
			(unlocked yes)
			(layer "B.Fab")
			(hide yes)
			(effects
				(font
					(size 1.016 1.016)
					(thickness 0.1524)
				)
				(justify mirror)
			)
		)
		(duplicate_pad_numbers_are_jumpers no)
		(fp_line
			(start 0.4064 0)
			(end -0.4064 0)
			(stroke
				(width 0.2032)
				(type default)
			)
			(layer "B.SilkS")
		)
		(fp_rect
			(start 0.635 1.1811)
			(end -0.635 -1.1811)
			(stroke
				(width 0)
				(type default)
			)
			(fill no)
			(layer "B.CrtYd")
		)
		(fp_rect
			(start 0.635 1.1811)
			(end -0.635 -1.1811)
			(stroke
				(width 0)
				(type default)
			)
			(fill no)
			(layer "B.Fab")
		)
		(pad "1" smd custom
			(at 0 -0.6604 90)
			(size 0.19685 0.19685)
			(layers "B.Cu" "B.Mask" "B.Paste")
			(net "P3V3")
			(options
				(clearance outline)
				(anchor circle)
			)
			(primitives
				(gr_poly
					(pts
						(arc
							(start 0.508 0.2921)
							(mid 0.478242 0.363942)
							(end 0.4064 0.3937)
						)
						(arc
							(start -0.4064 0.3937)
							(mid -0.478242 0.363942)
							(end -0.508 0.2921)
						)
						(arc
							(start -0.508 -0.2921)
							(mid -0.478242 -0.363942)
							(end -0.4064 -0.3937)
						)
						(arc
							(start 0.4064 -0.3937)
							(mid 0.478242 -0.363942)
							(end 0.508 -0.2921)
						)
					)
					(width 0)
					(fill yes)
				)
			)
		)
		(pad "2" smd custom
			(at 0 0.6604 90)
			(size 0.19685 0.19685)
			(layers "B.Cu" "B.Mask" "B.Paste")
			(net "P3V3_VDDA_CLKBUFF_R")
			(options
				(clearance outline)
				(anchor circle)
			)
			(primitives
				(gr_poly
					(pts
						(arc
							(start 0.508 0.2921)
							(mid 0.478242 0.363942)
							(end 0.4064 0.3937)
						)
						(arc
							(start -0.4064 0.3937)
							(mid -0.478242 0.363942)
							(end -0.508 0.2921)
						)
						(arc
							(start -0.508 -0.2921)
							(mid -0.478242 -0.363942)
							(end -0.4064 -0.3937)
						)
						(arc
							(start 0.4064 -0.3937)
							(mid 0.478242 -0.363942)
							(end 0.508 -0.2921)
						)
					)
					(width 0)
					(fill yes)
				)
			)
		)
	)
	(footprint ""
		(layer "B.Cu")
		(at 133.731 -38.481 -90)
		(property "Reference" "C135"
			(at 0 0 90)
			(layer "B.SilkS")
			(hide yes)
			(effects
				(font
					(size 1.27 1.27)
				)
				(justify mirror)
			)
		)
		(property "Value" "SCD1U10V2KX-5GP"
			(at -1.1811 -2.7051 270)
			(unlocked yes)
			(layer "B.Fab")
			(hide yes)
			(effects
				(font
					(size 1.016 1.016)
					(thickness 0.1524)
				)
				(justify mirror)
			)
		)
		(property "Device Type" "C402H22"
			(at -1.1811 -4.2291 270)
			(unlocked yes)
			(layer "B.Fab")
			(hide yes)
			(effects
				(font
					(size 1.016 1.016)
					(thickness 0.1524)
				)
				(justify mirror)
			)
		)
		(duplicate_pad_numbers_are_jumpers no)
		(fp_rect
			(start 0.381 0.7366)
			(end -0.381 -0.7366)
			(stroke
				(width 0)
				(type default)
			)
			(fill no)
			(layer "B.CrtYd")
		)
		(fp_rect
			(start 0.381 0.7366)
			(end -0.381 -0.7366)
			(stroke
				(width 0)
				(type default)
			)
			(fill no)
			(layer "B.Fab")
		)
		(pad "1" smd custom
			(at 0 -0.4572 90)
			(size 0.1143 0.1143)
			(layers "B.Cu" "B.Mask" "B.Paste")
			(net "P3V3_STBY")
			(options
				(clearance outline)
				(anchor circle)
			)
			(primitives
				(gr_poly
					(pts
						(arc
							(start -0.254 0.1778)
							(mid -0.239121 0.213721)
							(end -0.2032 0.2286)
						)
						(arc
							(start 0.2032 0.2286)
							(mid 0.239121 0.213721)
							(end 0.254 0.1778)
						)
						(arc
							(start 0.254 -0.1778)
							(mid 0.239121 -0.213721)
							(end 0.2032 -0.2286)
						)
						(arc
							(start -0.2032 -0.2286)
							(mid -0.239121 -0.213721)
							(end -0.254 -0.1778)
						)
					)
					(width 0)
					(fill yes)
				)
			)
		)
		(pad "2" smd custom
			(at 0 0.4572 90)
			(size 0.1143 0.1143)
			(layers "B.Cu" "B.Mask" "B.Paste")
			(net "GND")
			(options
				(clearance outline)
				(anchor circle)
			)
			(primitives
				(gr_poly
					(pts
						(arc
							(start -0.254 0.1778)
							(mid -0.239121 0.213721)
							(end -0.2032 0.2286)
						)
						(arc
							(start 0.2032 0.2286)
							(mid 0.239121 0.213721)
							(end 0.254 0.1778)
						)
						(arc
							(start 0.254 -0.1778)
							(mid 0.239121 -0.213721)
							(end 0.2032 -0.2286)
						)
						(arc
							(start -0.2032 -0.2286)
							(mid -0.239121 -0.213721)
							(end -0.254 -0.1778)
						)
					)
					(width 0)
					(fill yes)
				)
			)
		)
	)
	(footprint ""
		(layer "B.Cu")
		(at 36.957 -27.686 -90)
		(property "Reference" "R453"
			(at 0 0 90)
			(layer "B.SilkS")
			(hide yes)
			(effects
				(font
					(size 1.27 1.27)
				)
				(justify mirror)
			)
		)
		(property "Value" "4K7R2F-GP"
			(at -1.7907 -1.1176 270)
			(unlocked yes)
			(layer "B.Fab")
			(hide yes)
			(effects
				(font
					(size 1.016 1.016)
					(thickness 0.1524)
				)
				(justify mirror)
			)
		)
		(property "Device Type" "R402H16"
			(at -1.7907 -2.6416 270)
			(unlocked yes)
			(layer "B.Fab")
			(hide yes)
			(effects
				(font
					(size 1.016 1.016)
					(thickness 0.1524)
				)
				(justify mirror)
			)
		)
		(duplicate_pad_numbers_are_jumpers no)
		(fp_rect
			(start 0.381 0.8382)
			(end -0.381 -0.8382)
			(stroke
				(width 0)
				(type default)
			)
			(fill no)
			(layer "B.CrtYd")
		)
		(fp_rect
			(start 0.381 0.8382)
			(end -0.381 -0.8382)
			(stroke
				(width 0)
				(type default)
			)
			(fill no)
			(layer "B.Fab")
		)
		(pad "1" smd custom
			(at 0 -0.4318 90)
			(size 0.127 0.127)
			(layers "B.Cu" "B.Mask" "B.Paste")
			(net "CLKCUFF_SMB_ADDR")
			(options
				(clearance outline)
				(anchor circle)
			)
			(primitives
				(gr_poly
					(pts
						(arc
							(start -0.2032 0.2794)
							(mid -0.239121 0.264521)
							(end -0.254 0.2286)
						)
						(arc
							(start -0.254 -0.2286)
							(mid -0.239121 -0.264521)
							(end -0.2032 -0.2794)
						)
						(arc
							(start 0.2032 -0.2794)
							(mid 0.239121 -0.264521)
							(end 0.254 -0.2286)
						)
						(arc
							(start 0.254 0.2286)
							(mid 0.239121 0.264521)
							(end 0.2032 0.2794)
						)
					)
					(width 0)
					(fill yes)
				)
			)
		)
		(pad "2" smd custom
			(at 0 0.4318 90)
			(size 0.127 0.127)
			(layers "B.Cu" "B.Mask" "B.Paste")
			(net "GND")
			(options
				(clearance outline)
				(anchor circle)
			)
			(primitives
				(gr_poly
					(pts
						(arc
							(start -0.2032 0.2794)
							(mid -0.239121 0.264521)
							(end -0.254 0.2286)
						)
						(arc
							(start -0.254 -0.2286)
							(mid -0.239121 -0.264521)
							(end -0.2032 -0.2794)
						)
						(arc
							(start 0.2032 -0.2794)
							(mid 0.239121 -0.264521)
							(end 0.254 -0.2286)
						)
						(arc
							(start 0.254 0.2286)
							(mid 0.239121 0.264521)
							(end 0.2032 0.2794)
						)
					)
					(width 0)
					(fill yes)
				)
			)
		)
	)
	(footprint ""
		(layer "B.Cu")
		(at 100.074984 -33.290002 -90)
		(property "Reference" "C219"
			(at 0 0 90)
			(layer "B.SilkS")
			(hide yes)
			(effects
				(font
					(size 1.27 1.27)
				)
				(justify mirror)
			)
		)
		(property "Value" "SC1U10V2KX-1GP"
			(at -1.1811 -2.7051 270)
			(unlocked yes)
			(layer "B.Fab")
			(hide yes)
			(effects
				(font
					(size 1.016 1.016)
					(thickness 0.1524)
				)
				(justify mirror)
			)
		)
		(property "Device Type" "C402H22"
			(at -1.1811 -4.2291 270)
			(unlocked yes)
			(layer "B.Fab")
			(hide yes)
			(effects
				(font
					(size 1.016 1.016)
					(thickness 0.1524)
				)
				(justify mirror)
			)
		)
		(duplicate_pad_numbers_are_jumpers no)
		(fp_rect
			(start 0.381 0.7366)
			(end -0.381 -0.7366)
			(stroke
				(width 0)
				(type default)
			)
			(fill no)
			(layer "B.CrtYd")
		)
		(fp_rect
			(start 0.381 0.7366)
			(end -0.381 -0.7366)
			(stroke
				(width 0)
				(type default)
			)
			(fill no)
			(layer "B.Fab")
		)
		(pad "1" smd custom
			(at 0 -0.4572 90)
			(size 0.1143 0.1143)
			(layers "B.Cu" "B.Mask" "B.Paste")
			(net "P1V0")
			(options
				(clearance outline)
				(anchor circle)
			)
			(primitives
				(gr_poly
					(pts
						(arc
							(start -0.254 0.1778)
							(mid -0.239121 0.213721)
							(end -0.2032 0.2286)
						)
						(arc
							(start 0.2032 0.2286)
							(mid 0.239121 0.213721)
							(end 0.254 0.1778)
						)
						(arc
							(start 0.254 -0.1778)
							(mid 0.239121 -0.213721)
							(end 0.2032 -0.2286)
						)
						(arc
							(start -0.2032 -0.2286)
							(mid -0.239121 -0.213721)
							(end -0.254 -0.1778)
						)
					)
					(width 0)
					(fill yes)
				)
			)
		)
		(pad "2" smd custom
			(at 0 0.4572 90)
			(size 0.1143 0.1143)
			(layers "B.Cu" "B.Mask" "B.Paste")
			(net "GND")
			(options
				(clearance outline)
				(anchor circle)
			)
			(primitives
				(gr_poly
					(pts
						(arc
							(start -0.254 0.1778)
							(mid -0.239121 0.213721)
							(end -0.2032 0.2286)
						)
						(arc
							(start 0.2032 0.2286)
							(mid 0.239121 0.213721)
							(end 0.254 0.1778)
						)
						(arc
							(start 0.254 -0.1778)
							(mid 0.239121 -0.213721)
							(end 0.2032 -0.2286)
						)
						(arc
							(start -0.2032 -0.2286)
							(mid -0.239121 -0.213721)
							(end -0.254 -0.1778)
						)
					)
					(width 0)
					(fill yes)
				)
			)
		)
	)
	(footprint ""
		(layer "B.Cu")
		(at 9.017 -22.606 180)
		(property "Reference" "PR112"
			(at 0 0 0)
			(layer "B.SilkS")
			(hide yes)
			(effects
				(font
					(size 1.27 1.27)
				)
				(justify mirror)
			)
		)
		(property "Value" "100KR2F-L2-GP"
			(at -1.7907 -1.1176 180)
			(unlocked yes)
			(layer "B.Fab")
			(hide yes)
			(effects
				(font
					(size 1.016 1.016)
					(thickness 0.1524)
				)
				(justify mirror)
			)
		)
		(property "Device Type" "R402H16"
			(at -1.7907 -2.6416 180)
			(unlocked yes)
			(layer "B.Fab")
			(hide yes)
			(effects
				(font
					(size 1.016 1.016)
					(thickness 0.1524)
				)
				(justify mirror)
			)
		)
		(duplicate_pad_numbers_are_jumpers no)
		(fp_rect
			(start 0.381 0.8382)
			(end -0.381 -0.8382)
			(stroke
				(width 0)
				(type default)
			)
			(fill no)
			(layer "B.CrtYd")
		)
		(fp_rect
			(start 0.381 0.8382)
			(end -0.381 -0.8382)
			(stroke
				(width 0)
				(type default)
			)
			(fill no)
			(layer "B.Fab")
		)
		(pad "1" smd custom
			(at 0 -0.4318)
			(size 0.127 0.127)
			(layers "B.Cu" "B.Mask" "B.Paste")
			(net "P1V0_VREG")
			(options
				(clearance outline)
				(anchor circle)
			)
			(primitives
				(gr_poly
					(pts
						(arc
							(start -0.2032 0.2794)
							(mid -0.239121 0.264521)
							(end -0.254 0.2286)
						)
						(arc
							(start -0.254 -0.2286)
							(mid -0.239121 -0.264521)
							(end -0.2032 -0.2794)
						)
						(arc
							(start 0.2032 -0.2794)
							(mid 0.239121 -0.264521)
							(end 0.254 -0.2286)
						)
						(arc
							(start 0.254 0.2286)
							(mid 0.239121 0.264521)
							(end 0.2032 0.2794)
						)
					)
					(width 0)
					(fill yes)
				)
			)
		)
		(pad "2" smd custom
			(at 0 0.4318)
			(size 0.127 0.127)
			(layers "B.Cu" "B.Mask" "B.Paste")
			(net "P1V0_RF")
			(options
				(clearance outline)
				(anchor circle)
			)
			(primitives
				(gr_poly
					(pts
						(arc
							(start -0.2032 0.2794)
							(mid -0.239121 0.264521)
							(end -0.254 0.2286)
						)
						(arc
							(start -0.254 -0.2286)
							(mid -0.239121 -0.264521)
							(end -0.2032 -0.2794)
						)
						(arc
							(start 0.2032 -0.2794)
							(mid 0.239121 -0.264521)
							(end 0.254 -0.2286)
						)
						(arc
							(start 0.254 0.2286)
							(mid 0.239121 0.264521)
							(end 0.2032 0.2794)
						)
					)
					(width 0)
					(fill yes)
				)
			)
		)
	)
	(footprint ""
		(layer "B.Cu")
		(at 114.173 -67.691)
		(property "Reference" "C322"
			(at 0 0 0)
			(layer "B.SilkS")
			(hide yes)
			(effects
				(font
					(size 1.27 1.27)
				)
				(justify mirror)
			)
		)
		(property "Value" "SC22U6D3V5MX-2GP"
			(at 0 -4.9022 0)
			(unlocked yes)
			(layer "B.Fab")
			(hide yes)
			(effects
				(font
					(size 1.016 1.016)
					(thickness 0.1524)
				)
				(justify mirror)
			)
		)
		(property "Device Type" "C805H58"
			(at 0 -6.8072 0)
			(unlocked yes)
			(layer "B.Fab")
			(hide yes)
			(effects
				(font
					(size 1.016 1.016)
					(thickness 0.1524)
				)
				(justify mirror)
			)
		)
		(duplicate_pad_numbers_are_jumpers no)
		(fp_line
			(start -0.6096 0)
			(end 0.6096 0)
			(stroke
				(width 0.3048)
				(type default)
			)
			(layer "B.SilkS")
		)
		(fp_poly
			(pts
				(xy 0.9017 1.4351) (xy -0.9017 1.4351) (xy -0.9017 -1.4351) (xy 0.9017 -1.4351)
			)
			(stroke
				(width 0)
				(type default)
			)
			(fill no)
			(layer "B.CrtYd")
		)
		(fp_poly
			(pts
				(xy -0.9017 1.4351) (xy -0.9017 -1.4351) (xy 0.9017 -1.4351) (xy 0.9017 1.4351)
			)
			(stroke
				(width 0)
				(type default)
			)
			(fill no)
			(layer "B.Fab")
		)
		(pad "1" smd rect
			(at 0 -0.8382 180)
			(size 1.5494 0.9398)
			(layers "B.Cu" "B.Mask" "B.Paste")
			(net "P3V3_RTC")
		)
		(pad "2" smd rect
			(at 0 0.8382 180)
			(size 1.5494 0.9398)
			(layers "B.Cu" "B.Mask" "B.Paste")
			(net "GND")
		)
	)
)
